FILE_TYPE = MULTI_PHYS_TABLE;

PART 'NCP3284AMNTXG'

{========================================================================================}
:VALUE           | PART_TYPE | MATERIAL | PART_NUMBER    = STANDARD | LIFECYCLE          | PART_NUMBER   | JEDEC_TYPE   | DESCRIPTION                   | MANUFTR | MANUF_PN        | RD_CMPLS_LVL | CMPLS_LVL | FROM_PJ    | CLASS | DIP_SMD | DATA                    | EE_CHECK_LIST | FP_ECN              | PSL | CREATOR | STATUS | MSD  | ESD_CDM | ESD_HBM | ESD_MM | PIN_LENGTH_SHORT_PIN | PIN_LENGTH_LONG_PIN | CREATEDAY  ;
{========================================================================================}
 'NCP3284AMNTXG' | 'SMLF'    | 'IC'     | 'AL003284002'(!) = ''       | ''               | 'AL003284002' |'PQFN22_6X5'| 'IC (37P)NCP3284AMNTXG(PQFN)' | 'ONS'   | 'NCP3284AMNTXG' | 'EP(V1)'     | ''        | 'S6X-KIMI' | 'IC'  | ''      | 'ONS_NCP3284AMNTXG.pdf' | ''            | 'NCP3284AMNTXG.msg' | ''  | ''      | ''     | 'NA' | 'na'    | 'na'    | 'na'   | '0 MILS'             | '0 MILS'            | '20201130'
 'NCP3284AMNTXG' | 'SMLF'    | 'EMPTY'  | 'AL003284002'(!) = ''       | ''               | 'AL003284002' |'PQFN22_6X5'| 'IC (37P)NCP3284AMNTXG(PQFN)' | 'ONS'   | 'NCP3284AMNTXG' | 'EP(V1)'     | ''        | 'S6X-KIMI' | 'IC'  | ''      | 'ONS_NCP3284AMNTXG.pdf' | ''            | 'NCP3284AMNTXG.msg' | ''  | ''      | ''     | 'NA' | 'na'    | 'na'    | 'na'   | '0 MILS'             | '0 MILS'            | '20201130'

END_PART

END.

